#ISCELL
  pure_quanta quanta_title_block_c *
  *
#CELL
  pure_quanta q_cap *
  page78_i1
#CELL
  pure_quanta q_cap *
  page78_i10
#ISCELL
  logical_power universal_power *
  page78_i11
#CELL
  pure_quanta q_cap *
  page78_i12
#ISCELL
  logical_power universal_power *
  page78_i13
#CELL
  pure_quanta q_cap *
  page78_i14
#ISCELL
  logical_power universal_power *
  page78_i15
#CELL
  pure_quanta q_cap *
  page78_i16
#ISCELL
  logical_power universal_power *
  page78_i17
#CELL
  pure_quanta q_cap *
  page78_i18
#CELL
  pure_quanta q_cap *
  page78_i19
#ISCELL
  logical_power universal_power *
  page78_i2
#ISCELL
  logical_power universal_gnd *
  page78_i20
#CELL
  pure_quanta q_cap *
  page78_i21
#ISCELL
  logical_power universal_gnd *
  page78_i22
#CELL
  pure_quanta q_cap *
  page78_i23
#CELL
  pure_quanta q_cap *
  page78_i24
#CELL
  pure_quanta q_cap *
  page78_i25
#CELL
  pure_quanta q_cap *
  page78_i26
#CELL
  pure_quanta q_cap *
  page78_i27
#ISCELL
  logical_power universal_gnd *
  page78_i28
#CELL
  pure_quanta q_cap *
  page78_i29
#CELL
  pure_quanta q_cap *
  page78_i3
#CELL
  pure_quanta q_cap *
  page78_i30
#CELL
  pure_quanta q_cap *
  page78_i31
#CELL
  pure_quanta q_cap *
  page78_i32
#CELL
  pure_quanta q_cap *
  page78_i33
#CELL
  pure_quanta q_cap *
  page78_i34
#CELL
  pure_quanta q_cap *
  page78_i35
#CELL
  pure_quanta q_cap *
  page78_i36
#CELL
  pure_quanta q_cap *
  page78_i37
#CELL
  pure_quanta q_cap *
  page78_i38
#CELL
  pure_quanta q_cap *
  page78_i39
#CELL
  pure_quanta q_cap *
  page78_i4
#CELL
  pure_quanta q_cap *
  page78_i40
#CELL
  pure_quanta q_cap *
  page78_i41
#CELL
  pure_quanta q_cap *
  page78_i42
#CELL
  pure_quanta q_cap *
  page78_i43
#CELL
  pure_quanta q_cap *
  page78_i44
#CELL
  pure_quanta q_cap *
  page78_i45
#CELL
  pure_quanta q_cap *
  page78_i46
#ISCELL
  logical_power universal_power *
  page78_i47
#CELL
  pure_quanta q_cap *
  page78_i48
#CELL
  pure_quanta q_cap *
  page78_i49
#CELL
  pure_quanta q_cap *
  page78_i5
#ISCELL
  logical_power universal_power *
  page78_i50
#CELL
  pure_quanta q_cap *
  page78_i51
#CELL
  pure_quanta q_cap *
  page78_i52
#CELL
  pure_quanta q_cap *
  page78_i53
#ISCELL
  logical_power universal_gnd *
  page78_i54
#CELL
  pure_quanta q_cap *
  page78_i55
#ISCELL
  logical_power universal_gnd *
  page78_i56
#CELL
  pure_quanta q_cap *
  page78_i57
#CELL
  pure_quanta q_cap *
  page78_i58
#ISCELL
  logical_power universal_gnd *
  page78_i59
#ISCELL
  logical_power universal_gnd *
  page78_i6
#CELL
  pure_quanta q_cap *
  page78_i60
#ISCELL
  logical_power universal_gnd *
  page78_i61
#ISCELL
  logical_power universal_gnd *
  page78_i62
#CELL
  pure_quanta q_cap *
  page78_i63
#CELL
  pure_quanta q_cap *
  page78_i64
#CELL
  pure_quanta q_cap *
  page78_i65
#CELL
  pure_quanta q_cap *
  page78_i66
#ISCELL
  logical_power universal_power *
  page78_i67
#CELL
  pure_quanta q_cap *
  page78_i68
#CELL
  pure_quanta q_cap *
  page78_i7
#CELL
  pure_quanta q_cap *
  page78_i8
#ISCELL
  logical_power universal_power *
  page78_i9
